(kicad_pcb
	(version 20241229)
	(generator "pcbnew")
	(generator_version "9.0")
	(general
		(thickness 1.6642)
		(legacy_teardrops no)
	)
	(paper "A3")
	(title_block
		(title "PolarFire SoM")
		(date "2025-07-22")
		(rev "1.1.4")
		(company "Antmicro Ltd")
		(comment 1 "www.antmicro.com")
		(comment 9 "footprints 439-442 of 470")
	)
	(layers
		(0 "F.Cu" mixed)
		(4 "In1.Cu" power)
		(6 "In2.Cu" signal)
		(8 "In3.Cu" power)
		(10 "In4.Cu" signal)
		(12 "In5.Cu" power)
		(14 "In6.Cu" power)
		(16 "In7.Cu" signal)
		(18 "In8.Cu" power)
		(20 "In9.Cu" signal)
		(22 "In10.Cu" power)
		(24 "In11.Cu" signal)
		(26 "In12.Cu" signal)
		(2 "B.Cu" mixed)
		(9 "F.Adhes" user "F.Adhesive")
		(11 "B.Adhes" user "B.Adhesive")
		(13 "F.Paste" user)
		(15 "B.Paste" user)
		(5 "F.SilkS" user "F.Silkscreen")
		(7 "B.SilkS" user "B.Silkscreen")
		(1 "F.Mask" user)
		(3 "B.Mask" user)
		(17 "Dwgs.User" user "User.Drawings")
		(19 "Cmts.User" user "User.Comments")
		(21 "Eco1.User" user "User.Eco1")
		(23 "Eco2.User" user "User.Eco2")
		(25 "Edge.Cuts" user)
		(27 "Margin" user)
		(31 "F.CrtYd" user "F.Courtyard")
		(29 "B.CrtYd" user "B.Courtyard")
		(35 "F.Fab" user)
		(33 "B.Fab" user)
	)
	(footprint "antmicro-footprints:C_0402_1005Metric"
		(layer "B.Cu")
		(at 219.6 150.05 90)
		(descr "Capacitor SMD 0402")
		(tags "capacitor SMD 0402")
		(property "Reference" "C229"
			(at -1.99 1.37 90)
			(layer "B.SilkS")
			(effects
				(font
					(size 0.7 0.7)
					(thickness 0.15)
				)
				(justify right bottom mirror)
			)
		)
		(property "Value" "C_100n_0402"
			(at -1.022927 -2.155213 90)
			(layer "B.Fab")
			(hide yes)
			(effects
				(font
					(size 0.7 0.7)
					(thickness 0.15)
				)
				(justify right bottom mirror)
			)
		)
		(property "Datasheet" "https://www.murata.com/products/productdetail?partno=GRM155R61H104KE14%23"
			(at 0 0 90)
			(layer "F.Fab")
			(hide yes)
			(effects
				(font
					(size 1.27 1.27)
					(thickness 0.15)
				)
			)
		)
		(property "Description" "SMD Multilayer Ceramic Capacitor, 0.1 µF, 50 V, 0402 [1005 Metric], ± 10%, X5R, GRM Series"
			(at 0 0 90)
			(layer "F.Fab")
			(hide yes)
			(effects
				(font
					(size 1.27 1.27)
					(thickness 0.15)
				)
			)
		)
		(property "Author" "Antmicro"
			(at 369.65 -69.55 0)
			(layer "B.Fab")
			(hide yes)
			(effects
				(font
					(size 1 1)
					(thickness 0.15)
				)
				(justify mirror)
			)
		)
		(property "Dielectric" "X5R"
			(at 369.65 -69.55 0)
			(layer "B.Fab")
			(hide yes)
			(effects
				(font
					(size 1 1)
					(thickness 0.15)
				)
				(justify mirror)
			)
		)
		(property "License" "Apache-2.0"
			(at 369.65 -69.55 0)
			(layer "B.Fab")
			(hide yes)
			(effects
				(font
					(size 1 1)
					(thickness 0.15)
				)
				(justify mirror)
			)
		)
		(property "MPN" "GRM155R61H104KE14D"
			(at 369.65 -69.55 0)
			(layer "B.Fab")
			(hide yes)
			(effects
				(font
					(size 1 1)
					(thickness 0.15)
				)
				(justify mirror)
			)
		)
		(property "Manufacturer" "Murata"
			(at 369.65 -69.55 0)
			(layer "B.Fab")
			(hide yes)
			(effects
				(font
					(size 1 1)
					(thickness 0.15)
				)
				(justify mirror)
			)
		)
		(property "Public" ""
			(at 369.65 -69.55 0)
			(layer "B.Fab")
			(hide yes)
			(effects
				(font
					(size 1 1)
					(thickness 0.15)
				)
				(justify mirror)
			)
		)
		(property "Val" "100n"
			(at 369.65 -69.55 0)
			(layer "B.Fab")
			(hide yes)
			(effects
				(font
					(size 1 1)
					(thickness 0.15)
				)
				(justify mirror)
			)
		)
		(property "Voltage" "50V"
			(at 369.65 -69.55 0)
			(layer "B.Fab")
			(hide yes)
			(effects
				(font
					(size 1 1)
					(thickness 0.15)
				)
				(justify mirror)
			)
		)
		(sheetname "/WiFi_Bluetooth/")
		(sheetfile "wifi_bt.kicad_sch")
		(attr smd)
		(fp_rect
			(start -0.925 0.47)
			(end 0.925 -0.47)
			(stroke
				(width 0.05)
				(type default)
			)
			(fill no)
			(layer "B.CrtYd")
		)
		(fp_line
			(start 0.504 -0.248)
			(end -0.494 -0.248)
			(stroke
				(width 0.15)
				(type solid)
			)
			(layer "B.Fab")
		)
		(fp_line
			(start -0.494 -0.248)
			(end -0.494 0.25)
			(stroke
				(width 0.15)
				(type solid)
			)
			(layer "B.Fab")
		)
		(fp_line
			(start 0.504 0.25)
			(end 0.504 -0.248)
			(stroke
				(width 0.15)
				(type solid)
			)
			(layer "B.Fab")
		)
		(fp_line
			(start -0.494 0.25)
			(end 0.504 0.25)
			(stroke
				(width 0.15)
				(type solid)
			)
			(layer "B.Fab")
		)
		(fp_text user "License: Apache-2.0"
			(at -0.939 -5.799 270)
			(layer "B.Fab")
			(effects
				(font
					(size 0.7 0.7)
					(thickness 0.15)
				)
				(justify left bottom mirror)
			)
		)
		(fp_text user "Author: Antmicro"
			(at -0.939 -3.399 270)
			(layer "B.Fab")
			(effects
				(font
					(size 0.7 0.7)
					(thickness 0.15)
				)
				(justify left bottom mirror)
			)
		)
		(fp_text user "${REFERENCE}"
			(at -0.939 -4.599 270)
			(layer "B.Fab")
			(effects
				(font
					(size 0.7 0.7)
					(thickness 0.15)
				)
				(justify left bottom mirror)
			)
		)
		(pad "1" smd roundrect
			(at -0.48 0 90)
			(size 0.59 0.64)
			(layers "B.Cu" "B.Mask" "B.Paste")
			(roundrect_rratio 0.25)
			(net 417 "GND")
			(pintype "passive")
		)
		(pad "2" smd roundrect
			(at 0.48 0 90)
			(size 0.59 0.64)
			(layers "B.Cu" "B.Mask" "B.Paste")
			(roundrect_rratio 0.25)
			(net 50 "+3V3")
			(pintype "passive")
		)
	)
	(footprint "antmicro-footprints:R_0402_1005Metric"
		(layer "B.Cu")
		(at 210.5 147 90)
		(descr "Resistor SMD 0402")
		(tags "resistor SMD 0402")
		(property "Reference" "R86"
			(at -0.92 0.3 270)
			(layer "B.SilkS")
			(effects
				(font
					(size 0.7 0.7)
					(thickness 0.15)
				)
				(justify left bottom mirror)
			)
		)
		(property "Value" "R_10k_0402"
			(at -1.011843 -1.772047 270)
			(layer "B.Fab")
			(hide yes)
			(effects
				(font
					(size 0.7 0.7)
					(thickness 0.15)
				)
				(justify left bottom mirror)
			)
		)
		(property "Datasheet" "https://www.bourns.com/docs/product-datasheets/cr.pdf"
			(at 0 0 90)
			(layer "F.Fab")
			(hide yes)
			(effects
				(font
					(size 1.27 1.27)
					(thickness 0.15)
				)
			)
		)
		(property "Description" "SMD Chip Resistor, 10 kohm, ± 1%, 62.5 mW, 0402 [1005 Metric], Thick Film, General Purpose"
			(at 0 0 90)
			(layer "F.Fab")
			(hide yes)
			(effects
				(font
					(size 1.27 1.27)
					(thickness 0.15)
				)
			)
		)
		(property "Author" "Antmicro"
			(at 357.5 -63.5 0)
			(layer "B.Fab")
			(hide yes)
			(effects
				(font
					(size 1 1)
					(thickness 0.15)
				)
				(justify mirror)
			)
		)
		(property "License" "Apache-2.0"
			(at 357.5 -63.5 0)
			(layer "B.Fab")
			(hide yes)
			(effects
				(font
					(size 1 1)
					(thickness 0.15)
				)
				(justify mirror)
			)
		)
		(property "MPN" "CR0402-FX-1002GLF"
			(at 357.5 -63.5 0)
			(layer "B.Fab")
			(hide yes)
			(effects
				(font
					(size 1 1)
					(thickness 0.15)
				)
				(justify mirror)
			)
		)
		(property "Manufacturer" "Bourns"
			(at 357.5 -63.5 0)
			(layer "B.Fab")
			(hide yes)
			(effects
				(font
					(size 1 1)
					(thickness 0.15)
				)
				(justify mirror)
			)
		)
		(property "Public" ""
			(at 357.5 -63.5 0)
			(layer "B.Fab")
			(hide yes)
			(effects
				(font
					(size 1 1)
					(thickness 0.15)
				)
				(justify mirror)
			)
		)
		(property "Tolerance" "1%"
			(at 357.5 -63.5 0)
			(layer "B.Fab")
			(hide yes)
			(effects
				(font
					(size 1 1)
					(thickness 0.15)
				)
				(justify mirror)
			)
		)
		(property "Val" "10k"
			(at 357.5 -63.5 0)
			(layer "B.Fab")
			(hide yes)
			(effects
				(font
					(size 1 1)
					(thickness 0.15)
				)
				(justify mirror)
			)
		)
		(sheetname "/USB/")
		(sheetfile "usb.kicad_sch")
		(attr smd)
		(fp_rect
			(start -0.925 0.47)
			(end 0.925 -0.47)
			(stroke
				(width 0.05)
				(type default)
			)
			(fill no)
			(layer "B.CrtYd")
		)
		(fp_rect
			(start -0.5 0.25)
			(end 0.5 -0.25)
			(stroke
				(width 0.15)
				(type solid)
			)
			(fill no)
			(layer "B.Fab")
		)
		(fp_text user "Author: Antmicro"
			(at -0.95 -4.169 270)
			(layer "B.Fab")
			(effects
				(font
					(size 0.7 0.7)
					(thickness 0.15)
				)
				(justify left bottom mirror)
			)
		)
		(fp_text user "${REFERENCE}"
			(at -0.95 -3.168 270)
			(layer "B.Fab")
			(effects
				(font
					(size 0.7 0.7)
					(thickness 0.15)
				)
				(justify left bottom mirror)
			)
		)
		(fp_text user "License: Apache-2.0"
			(at -0.95 -5.169 270)
			(layer "B.Fab")
			(effects
				(font
					(size 0.7 0.7)
					(thickness 0.15)
				)
				(justify left bottom mirror)
			)
		)
		(pad "1" smd roundrect
			(at -0.48 0 90)
			(size 0.59 0.64)
			(layers "B.Cu" "B.Mask" "B.Paste")
			(roundrect_rratio 0.25)
			(net 635 "/FPGA GPIO/ULPI.RESET")
			(pintype "passive")
		)
		(pad "2" smd roundrect
			(at 0.48 0 90)
			(size 0.59 0.64)
			(layers "B.Cu" "B.Mask" "B.Paste")
			(roundrect_rratio 0.25)
			(net 649 "VDD")
			(pintype "passive")
		)
	)
	(footprint "antmicro-footprints:R_0402_1005Metric"
		(layer "B.Cu")
		(at 216.37 148.58 180)
		(descr "Resistor SMD 0402")
		(tags "resistor SMD 0402")
		(property "Reference" "R164"
			(at -2.92 -3.81 0)
			(layer "B.SilkS")
			(effects
				(font
					(size 0.7 0.7)
					(thickness 0.15)
				)
				(justify left bottom mirror)
			)
		)
		(property "Value" "R_100k_0402"
			(at -1.011843 -1.772047 0)
			(layer "B.Fab")
			(hide yes)
			(effects
				(font
					(size 0.7 0.7)
					(thickness 0.15)
				)
				(justify left bottom mirror)
			)
		)
		(property "Datasheet" "https://www.bourns.com/docs/product-datasheets/cr.pdf"
			(at 0 0 180)
			(layer "F.Fab")
			(hide yes)
			(effects
				(font
					(size 1.27 1.27)
					(thickness 0.15)
				)
			)
		)
		(property "Description" "SMD Chip Resistor, 100 kohm, ± 1%, 62.5 mW, 0402 [1005 Metric], Thick Film, General Purpose"
			(at 0 0 180)
			(layer "F.Fab")
			(hide yes)
			(effects
				(font
					(size 1.27 1.27)
					(thickness 0.15)
				)
			)
		)
		(property "Author" "Antmicro"
			(at 432.74 297.16 0)
			(layer "B.Fab")
			(hide yes)
			(effects
				(font
					(size 1 1)
					(thickness 0.15)
				)
				(justify mirror)
			)
		)
		(property "License" "Apache-2.0"
			(at 432.74 297.16 0)
			(layer "B.Fab")
			(hide yes)
			(effects
				(font
					(size 1 1)
					(thickness 0.15)
				)
				(justify mirror)
			)
		)
		(property "MPN" "CR0402-FX-1003GLF"
			(at 432.74 297.16 0)
			(layer "B.Fab")
			(hide yes)
			(effects
				(font
					(size 1 1)
					(thickness 0.15)
				)
				(justify mirror)
			)
		)
		(property "Manufacturer" "Bourns"
			(at 432.74 297.16 0)
			(layer "B.Fab")
			(hide yes)
			(effects
				(font
					(size 1 1)
					(thickness 0.15)
				)
				(justify mirror)
			)
		)
		(property "Public" ""
			(at 432.74 297.16 0)
			(layer "B.Fab")
			(hide yes)
			(effects
				(font
					(size 1 1)
					(thickness 0.15)
				)
				(justify mirror)
			)
		)
		(property "Tolerance" "1%"
			(at 432.74 297.16 0)
			(layer "B.Fab")
			(hide yes)
			(effects
				(font
					(size 1 1)
					(thickness 0.15)
				)
				(justify mirror)
			)
		)
		(property "Val" "100k"
			(at 432.74 297.16 0)
			(layer "B.Fab")
			(hide yes)
			(effects
				(font
					(size 1 1)
					(thickness 0.15)
				)
				(justify mirror)
			)
		)
		(sheetname "/USB/")
		(sheetfile "usb.kicad_sch")
		(attr smd)
		(fp_rect
			(start -0.925 0.47)
			(end 0.925 -0.47)
			(stroke
				(width 0.05)
				(type default)
			)
			(fill no)
			(layer "B.CrtYd")
		)
		(fp_rect
			(start -0.5 0.25)
			(end 0.5 -0.25)
			(stroke
				(width 0.15)
				(type solid)
			)
			(fill no)
			(layer "B.Fab")
		)
		(fp_text user "${REFERENCE}"
			(at -0.95 -3.168 0)
			(layer "B.Fab")
			(effects
				(font
					(size 0.7 0.7)
					(thickness 0.15)
				)
				(justify left bottom mirror)
			)
		)
		(fp_text user "Author: Antmicro"
			(at -0.95 -4.169 0)
			(layer "B.Fab")
			(effects
				(font
					(size 0.7 0.7)
					(thickness 0.15)
				)
				(justify left bottom mirror)
			)
		)
		(fp_text user "License: Apache-2.0"
			(at -0.95 -5.169 0)
			(layer "B.Fab")
			(effects
				(font
					(size 0.7 0.7)
					(thickness 0.15)
				)
				(justify left bottom mirror)
			)
		)
		(pad "1" smd roundrect
			(at -0.48 0 180)
			(size 0.59 0.64)
			(layers "B.Cu" "B.Mask" "B.Paste")
			(roundrect_rratio 0.25)
			(net 317 "/USB/~{HUB_RST}")
			(pintype "passive")
		)
		(pad "2" smd roundrect
			(at 0.48 0 180)
			(size 0.59 0.64)
			(layers "B.Cu" "B.Mask" "B.Paste")
			(roundrect_rratio 0.25)
			(net 50 "+3V3")
			(pintype "passive")
		)
	)
	(footprint "antmicro-footprints:C_0402_1005Metric"
		(layer "B.Cu")
		(at 210.5516 121.416)
		(descr "Capacitor SMD 0402")
		(tags "capacitor SMD 0402")
		(property "Reference" "C258"
			(at -3.5766 2.659 0)
			(layer "B.SilkS")
			(effects
				(font
					(size 0.7 0.7)
					(thickness 0.15)
				)
				(justify right bottom mirror)
			)
		)
		(property "Value" "C_100n_0402"
			(at -1.022927 -2.155213 0)
			(layer "B.Fab")
			(hide yes)
			(effects
				(font
					(size 0.7 0.7)
					(thickness 0.15)
				)
				(justify right bottom mirror)
			)
		)
		(property "Datasheet" "https://www.murata.com/products/productdetail?partno=GRM155R61H104KE14%23"
			(at 0 0 0)
			(layer "F.Fab")
			(hide yes)
			(effects
				(font
					(size 1.27 1.27)
					(thickness 0.15)
				)
			)
		)
		(property "Description" "SMD Multilayer Ceramic Capacitor, 0.1 µF, 50 V, 0402 [1005 Metric], ± 10%, X5R, GRM Series"
			(at 0 0 0)
			(layer "F.Fab")
			(hide yes)
			(effects
				(font
					(size 1.27 1.27)
					(thickness 0.15)
				)
			)
		)
		(property "Author" "Antmicro"
			(at 0 0 0)
			(layer "B.Fab")
			(hide yes)
			(effects
				(font
					(size 1 1)
					(thickness 0.15)
				)
				(justify mirror)
			)
		)
		(property "DNP" "DNP"
			(at 0 0 0)
			(layer "B.Fab")
			(hide yes)
			(effects
				(font
					(size 1 1)
					(thickness 0.15)
				)
				(justify mirror)
			)
		)
		(property "Dielectric" "X5R"
			(at 0 0 0)
			(layer "B.Fab")
			(hide yes)
			(effects
				(font
					(size 1 1)
					(thickness 0.15)
				)
				(justify mirror)
			)
		)
		(property "License" "Apache-2.0"
			(at 0 0 0)
			(layer "B.Fab")
			(hide yes)
			(effects
				(font
					(size 1 1)
					(thickness 0.15)
				)
				(justify mirror)
			)
		)
		(property "MPN" "GRM155R61H104KE14D"
			(at 0 0 0)
			(layer "B.Fab")
			(hide yes)
			(effects
				(font
					(size 1 1)
					(thickness 0.15)
				)
				(justify mirror)
			)
		)
		(property "Manufacturer" "Murata"
			(at 0 0 0)
			(layer "B.Fab")
			(hide yes)
			(effects
				(font
					(size 1 1)
					(thickness 0.15)
				)
				(justify mirror)
			)
		)
		(property "Public" ""
			(at 0 0 0)
			(layer "B.Fab")
			(hide yes)
			(effects
				(font
					(size 1 1)
					(thickness 0.15)
				)
				(justify mirror)
			)
		)
		(property "Val" "100n"
			(at 0 0 0)
			(layer "B.Fab")
			(hide yes)
			(effects
				(font
					(size 1 1)
					(thickness 0.15)
				)
				(justify mirror)
			)
		)
		(property "Voltage" "50V"
			(at 0 0 0)
			(layer "B.Fab")
			(hide yes)
			(effects
				(font
					(size 1 1)
					(thickness 0.15)
				)
				(justify mirror)
			)
		)
		(sheetname "/Ethernet/")
		(sheetfile "ethernet.kicad_sch")
		(attr smd dnp)
		(fp_rect
			(start -0.925 0.47)
			(end 0.925 -0.47)
			(stroke
				(width 0.05)
				(type default)
			)
			(fill no)
			(layer "B.CrtYd")
		)
		(fp_line
			(start -0.494 -0.248)
			(end -0.494 0.25)
			(stroke
				(width 0.15)
				(type solid)
			)
			(layer "B.Fab")
		)
		(fp_line
			(start -0.494 0.25)
			(end 0.504 0.25)
			(stroke
				(width 0.15)
				(type solid)
			)
			(layer "B.Fab")
		)
		(fp_line
			(start 0.504 -0.248)
			(end -0.494 -0.248)
			(stroke
				(width 0.15)
				(type solid)
			)
			(layer "B.Fab")
		)
		(fp_line
			(start 0.504 0.25)
			(end 0.504 -0.248)
			(stroke
				(width 0.15)
				(type solid)
			)
			(layer "B.Fab")
		)
		(fp_text user "License: Apache-2.0"
			(at -0.939 -5.799 180)
			(layer "B.Fab")
			(effects
				(font
					(size 0.7 0.7)
					(thickness 0.15)
				)
				(justify left bottom mirror)
			)
		)
		(fp_text user "${REFERENCE}"
			(at -0.939 -4.599 180)
			(layer "B.Fab")
			(effects
				(font
					(size 0.7 0.7)
					(thickness 0.15)
				)
				(justify left bottom mirror)
			)
		)
		(fp_text user "Author: Antmicro"
			(at -0.939 -3.399 180)
			(layer "B.Fab")
			(effects
				(font
					(size 0.7 0.7)
					(thickness 0.15)
				)
				(justify left bottom mirror)
			)
		)
		(pad "1" smd roundrect
			(at -0.48 0)
			(size 0.59 0.64)
			(layers "B.Cu" "B.Mask" "B.Paste")
			(roundrect_rratio 0.25)
			(net 10 "MSS_REFCLK_P")
			(pintype "passive")
		)
		(pad "2" smd roundrect
			(at 0.48 0)
			(size 0.59 0.64)
			(layers "B.Cu" "B.Mask" "B.Paste")
			(roundrect_rratio 0.25)
			(net 169 "/Ethernet/SGMII_CO_P")
			(pintype "passive")
		)
	)
)
